# BASEBOARD_FAB2 (Tioga Pass) — schematic parts with pin connectivity, parts 3939–4100 of 4751; source: Cadence DE-HDL packaged netlist (pstxprt.dat, pstxnet.dat, pstchip.dat)

R8F7  RES  33.2 1% CHIP  pkg 0402  page 153 : 1 = SPI_SWITCH_CLK ; 2 = SPI_CLK_R1
R8F8  RES  33.2 1% CHIP  pkg 0402  page 153 : 1 = SPI_SWITCH_CLK ; 2 = SPI_CLK_R0
R8F9  RES  49.9K 1% CHIP  pkg 0402  page 240 : 1 = VR_P3V3_STBY_OCSELECT ; 2 = AGND_P3V3_STBY
R8F10  RES  22.1 1.0% CHIP  pkg 0402  page 240 : 1 = PWRGD_P3V3_STBY_R ; 2 = PWRGD_P3V3_STBY
R8F11  RES  0.0 5% CHIP  pkg 0402  page 240 : 1 = GND ; 2 = AGND_P3V3_STBY
R8F12  RES  33.2 1% CHIP  pkg 0402  page 162 : 1 = SPI_BMC_BT_DI ; 2 = SPI_BMC_BT_DI_R
R8F13  RES  4.75K 1% CHIP  pkg 0402  page 162 : 1 = P3V3_STBY ; 2 = SPI_BMC_BT_CS_N
R8F14  RES  4.75K 1% CHIP  pkg 0402  page 162 : 1 = P3V3_STBY ; 2 = PU_SPI_BMC_BT_HOLD_N
R8F16  RES  4.75K 1% EMPTY  pkg 0402  page 162 : 1 = P3V3_STBY ; 2 = PU_SPI_FLASH_RESET_2_N
R8F18  RES  0.0 5% CHIP  pkg 0402  page 185 : 1 = P3E_PCH_RX_0_DP ; 2 = P3E_PCH_M2_SATA6G_RX_R_DP
R8F21  RES  0.0 5% CHIP  pkg 0402  page 185 : 1 = P3E_PCH_RX_0_DN ; 2 = P3E_PCH_M2_SATA6G_RX_R_DN
R8F23  RES  2.21K 1% CHIP  pkg 0402  page 157 : 1 = P3V3_STBY ; 2 = IRQ_MEZZ_LAN_ALERT_N
R8F24  RES  4.75K 1% CHIP  pkg 0402  page 157 : 1 = P3V3_STBY ; 2 = FP_NMI_BTN_N
R8F25  RES  475.0 1% CHIP  pkg 0402  page 101 : 1 = A_COMP_CKMNG ; 2 = GND
R8F26  RES  10.0K 1% CHIP  pkg 0402  page 156 : 1 = P3V3_STBY ; 2 = FM_PCH_PWRBTN_R_N
R8F27  RES  33.2 1% CHIP  pkg 0402  page 101 : 1 = CLK_32K_SUSCLK_PLD_R ; 2 = CLK_32K_SUSCLK_PLD
R8F29  RES  33.2 1% CHIP  pkg 0402  page 101 : 1 = CLK_25M_BMC_R ; 2 = CLK_25M_BMC
R8F34  RES  4.75K 1% CHIP  pkg 0402  page 162 : 1 = P3V3_STBY ; 2 = PU_SPI_BMC_BT_WP_N
R8F35  RES  1.00K 1% EMPTY  pkg 0402  page 162 : 1 = PU_SPI_BMC_BT_WP_N ; 2 = GND
R8F36  RES  10.0K 1% CHIP  pkg 0402  page 185 : 1 = P3V3 ; 2 = PU_M2_CLK_REQ_N
R8F37  RES  0.0 5% EMPTY  pkg 0402  page 93 : 1 = FM_CPU_ERR0_LVT3_N ; 2 = FM_CPU_ERR0_PCH_N
R8F38  RES  0.0 5% CHIP  pkg 0402  page 93 : 1 = FM_CPU_ERR0_LVT3_N ; 2 = FM_CPU_ERR0_LVT3_BMC_N
R8G1  RES  22.1 1.0% CHIP  pkg 0402  page 101 : 1 = CLK_50M_CKMNG_BMC_2_R ; 2 = CLK_50M_CKMNG_BMC_2
R8G2  RES  4.75K 1% CHIP  pkg 0402  page 156 : 1 = P3V3_STBY ; 2 = FM_PCH_PWRBTN_OUT_N
R8G3  RES  2.26K 1.0% EMPTY  pkg 0402  page 159 : 1 = P3V3_STBY ; 2 = SMB_OCP_LAN_STBY_LVC3_SCL_R
R8G4  RES  20.0 1% CHIP  pkg 0402  page 159 : 1 = SMB_OCP_LAN_STBY_LVC3_SCL_R ; 2 = SMB_OCP_LAN_STBY_LVC3_SCL
R8G5  RES  20.0 1% CHIP  pkg 0402  page 159 : 1 = SMB_OCP_LAN_STBY_LVC3_SDA_R ; 2 = SMB_OCP_LAN_STBY_LVC3_SDA
R8G6  RES  2.26K 1.0% EMPTY  pkg 0402  page 159 : 1 = P3V3_STBY ; 2 = SMB_OCP_LAN_STBY_LVC3_SDA_R
R8G7  RES  0.0 5% CHIP  pkg 0402  page 189 : 1 = JTAG_PLD_TDI ; 2 = JTAG_PLD_TDI_MUX
R8G8  RES  0.0 5% CHIP  pkg 0402  page 189 : 1 = JTAG_BMC_TDI ; 2 = JTAG_TDI
R8G9  RES  0.0 5% EMPTY  pkg 0402  page 189 : 1 = JTAG_PCH_GBE_TRST_N ; 2 = JTAG_TRST_N
R8G10  RES  0.0 5% CHIP  pkg 0402  page 189 : 1 = JTAG_BMC_TRST_N ; 2 = JTAG_TRST_N
R8G11  RES  0.0 5% EMPTY  pkg 0402  page 189 : 1 = JTAG_PCH_PLD_TMS ; 2 = JTAG_TMS
R8G12  RES  0.0 5% EMPTY  pkg 0402  page 189 : 1 = JTAG_PCH_GBE_TMS ; 2 = JTAG_TMS
R8G13  RES  0.0 5% CHIP  pkg 0402  page 189 : 1 = JTAG_PLD_TMS ; 2 = JTAG_PLD_TMS_MUX
R8G14  RES  0.0 5% CHIP  pkg 0402  page 189 : 1 = JTAG_BMC_TMS ; 2 = JTAG_TMS
R8G15  RES  0.0 5% EMPTY  pkg 0402  page 189 : 1 = JTAG_PCH_GBE_CLK ; 2 = JTAG_TCK
R8G16  RES  0.0 5% EMPTY  pkg 0402  page 189 : 1 = JTAG_PCH_PLD_TCK ; 2 = JTAG_TCK
R8G17  RES  0.0 5% CHIP  pkg 0402  page 189 : 1 = JTAG_BMC_TCK ; 2 = JTAG_TCK
R8G18  RES  0.0 5% CHIP  pkg 0402  page 189 : 1 = JTAG_PLD_TCK ; 2 = JTAG_PLD_TCK_MUX
R8G19  RES  0.0 5% CHIP  pkg 0402  page 189 : 1 = JTAG_TDI ; 2 = JTAG_TDI_R
R8G20  RES  10.0K 1% CHIP  pkg 0402  page 189 : 1 = P3V3_STBY ; 2 = JTAG_TMS_R
R8G21  RES  0.0 5% CHIP  pkg 0402  page 189 : 1 = JTAG_TMS ; 2 = JTAG_TMS_R
R8G22  RES  0.0 5% CHIP  pkg 0402  page 189 : 1 = JTAG_TCK ; 2 = JTAG_TCK_R
R8G23  RES  4.75K 1% CHIP  pkg 0402  page 189 : 1 = JTAG_TCK_R ; 2 = GND
R8G24  RES  22.1 1.0% CHIP  pkg 0402  page 101 : 1 = CLK_50M_CKMNG_PCH_10GBE_R ; 2 = CLK_50M_CKMNG_PCH_10GBE
R8G25  RES  22.1 1.0% CHIP  pkg 0402  page 101 : 1 = CLK_50M_CKMNG_SPRVLLE_R ; 2 = CLK_50M_CKMNG_SPRVLLE
R8N1  RES  1.8K 1% CHIP  pkg 0402  page 55 : 1 = P3V3_STBY ; 2 = FM_CPU1_PROC_ID1
R8N2  RES  10.0K 1% CHIP  pkg 0402  page 55 : 1 = P3V3_STBY ; 2 = FM_CPU1_PKGID0
R8N3  RES  10.0K 1% CHIP  pkg 0402  page 55 : 1 = P3V3_STBY ; 2 = FM_CPU1_PKGID2
R8N4  RES  1.8K 1% CHIP  pkg 0402  page 55 : 1 = P3V3_STBY ; 2 = FM_CPU1_PROC_ID0
R8N5  RES  10.0K 1% CHIP  pkg 0402  page 55 : 1 = P3V3_STBY ; 2 = FM_CPU1_PKGID1
R8P1  RES  49.9 1% CHIP  pkg 0402  page 90 : 1 = PD_CPU1_TEST14 ; 2 = GND
R8P2  RES  49.9 1% CHIP  pkg 0402  page 90 : 1 = PD_CPU1_TEST13 ; 2 = GND
R8P3  RES  49.9 1% CHIP  pkg 0402  page 56 : 1 = PD_CPU1_RSVD_TEST_2 ; 2 = GND
R8R1  RES  49.9 1% CHIP  pkg 0402  page 56 : 1 = PD_CPU1_RSVD_TEST_1 ; 2 = GND
R8W1  RES  0.0 5% CHIP  pkg 0402  page 249 : 1 = BMC_SELF_HW_D_RST ; 2 = FM_TPM_PRES_RST_N
R8W2  RES  1.00K 1% CHIP  pkg 0402  page 235 : 1 = PU_PVNN_PCH_VCLK ; 2 = VR_PVNN_P1V05_PCH_VD12
R8W3  RES  1.00K 1% CHIP  pkg 0402  page 235 : 1 = VR_PVNN_P1V05_PCH_VD12 ; 2 = PU_PVNN_PCH_VDIO
R8W4  RES  20.0 1% CHIP  pkg 0402  page 138 : 1 = SMB_HOST_STBY_LVC3_SDA ; 2 = SMB_HOST_STBY_LVC3_SDA_R5
R8W5  RES  20.0 1% CHIP  pkg 0402  page 138 : 1 = SMB_HOST_STBY_LVC3_SCL ; 2 = SMB_HOST_STBY_LVC3_SCL_R5
R8W6  RES  1.37K 1% CHIP  pkg 0402  page 138 : 1 = P3V3_STBY ; 2 = SMB_VR_STBY_LVC3_SDA_R1
R8W7  RES  1.37K 1% CHIP  pkg 0402  page 138 : 1 = P3V3_STBY ; 2 = SMB_VR_STBY_LVC3_SCL_R1
R8W8  RES  1.00K 1% CHIP  pkg 0402  page 235 : 1 = P3V3_STBY ; 2 = PU_PVNN_PCH_PINALRT_N
R8W9  RES  4.75K 1% CHIP  pkg 0402  page 89 : 1 = P3V3_STBY ; 2 = IRQ_DIMM_SAVE_LVT3_CPU1
R8W10  RES  0.0 5% CHIP  pkg 0402  page 245 : 1 = JTAG_RISER_TMS ; 2 = JTAG_PLD_TMS_MUX
R8W11  RES  0.0 5% CHIP  pkg 0402  page 245 : 1 = JTAG_RISER_TCK ; 2 = JTAG_PLD_TCK_MUX
R8W12  RES  0.0 5% CHIP  pkg 0402  page 245 : 1 = JTAG_RISER_TRST ; 2 = JTAG_BMC_TRST_N
R8W13  RES  0.0 5% CHIP  pkg 0402  page 245 : 1 = JTAG_RISER_TDI_R ; 2 = JTAG_RISER_TDI
R8W14  RES  0.0 5% CHIP  pkg 0402  page 245 : 1 = JTAG_RISER_TDO_R ; 2 = JTAG_RISER_TDO
R8W15  RES  4.75K 1% CHIP  pkg 0402  page 245 : 1 = P3V3_STBY ; 2 = JTAG_RISER_N
R9A1  RES  1.00K 1% EMPTY  pkg 0402  page 111 : 1 = P3V3 ; 2 = XDP_CPU_TCK_BUF
R9A2  RES  33.2 1% EMPTY  pkg 0402  page 111 : 1 = XDP_PCH_CPU_TCK0 ; 2 = XDP_CPU_GTL_TCK_R2
R9A3  RES  0.0 5% CHIP  pkg 0402  page 111 : 1 = XDP_PCH_CPU_TCK0 ; 2 = XDP_CPU_TCK0
R9A4  RES  475.0 1% CHIP  pkg 0402  page 111 : 1 = CPU_XDP_PRESENT_N ; 2 = PVCCIO_CPU0
R9A5  RES  20.0K 1% CHIP  pkg 0402  page 155 : 1 = P5V_STBY ; 2 = FM_UART_SWITCH_N
R9A7  RES  2.21K 1% CHIP  pkg 0402  page 155 : 1 = P3V3_STBY ; 2 = SPA_SIN_SW_R
R9A8  RES  0.0 5% CHIP  pkg 0402  page 155 : 1 = SPA_SIN_SW_R ; 2 = SPA_MID_DBG1_RX
R9A9  RES  100.0 1% CHIP  pkg 0402  page 175 : 1 = RST_SYSTEM_BTN_BUF_N ; 2 = RST_SYSTEM_BTN_N
R9A11  RES  150.0 1% CHIP  pkg 0402  page 112 : 1 = P1V05_PCH_STBY ; 2 = XDP_TDO
R9A12  RES  2.21K 1% CHIP  pkg 0402  page 135 : 1 = FM_PCH_SATA_RAID_KEY_R ; 2 = P3V3_STBY
R9A13  RES  33.2 1% CHIP  pkg 0402  page 135 : 1 = FM_PCH_SATA_RAID_KEY_R ; 2 = FM_PCH_SATA_RAID_KEY
R9A14  RES  1.00K 1% CHIP  pkg 0402  page 111 : 1 = XDP_RST_CO_N ; 2 = P3V3_STBY
R9A15  RES  1.00K 1% CHIP  pkg 0402  page 111 : 1 = RST_RSMRST_N ; 2 = XDP_RSMRST_N
R9A16  RES  2.21K 1% CHIP  pkg 0402  page 135 : 1 = PU_KEY_CONN_PIN2_R ; 2 = P3V3_STBY
R9A17  RES  1.00K 1% CHIP  pkg 0402  page 111 : 1 = XDP_ITP_PMODE ; 2 = P1V05_PCH_STBY
R9A18  RES  4.75K 1% CHIP  pkg 0402  page 119 : 1 = P3V3_STBY ; 2 = FM_PWR_LED
R9A20  RES  221 1.0% CHIP  pkg 0402  page 119 : 1 = FM_PWR_LED_A ; 2 = P3V3_STBY
R9A21  RES  4.75K 1% CHIP  pkg 0402  page 119 : 1 = P3V3_STBY ; 2 = FM_PWR_LED_N
R9B4  RES  49.9 1% CHIP  pkg 0402  page 167 : 1 = ISENSE_TMP421_1_E ; 2 = ISENSE_TMP421_1_DXP
R9B5  RES  49.9 1% CHIP  pkg 0402  page 167 : 1 = ISENSE_TMP421_1_BC ; 2 = ISENSE_TMP421_1_DXN
R9B6  RES  1.00K 1% CHIP  pkg 0402  page 167 : 1 = P3V3_STBY ; 2 = PU_TMP421_1_A1
R9B7  887R2F-L-GP  1%  pkg SMD-RG  page 186 : 1 = FM_MEZZA_PRSNT1_N ; 2 = GND
R9B8  RES  1.00K 1% CHIP  pkg 0402  page 167 : 1 = PD_TMP421_1_A0 ; 2 = GND
R9B9  RES  1.00K 1% CHIP  pkg 0402  page 113 : 1 = JTAG_MCP_TCK ; 2 = GND
R9B10  RES  49.9 1% CHIP  pkg 0402  page 113 : 1 = JTAG_MCP_TCK ; 2 = JTAG_MCP_TCK_R1
R9B11  RES  0.0 5% CHIP  pkg 0402  page 113 : 1 = JTAG_MCP_TCK ; 2 = JTAG_MCP_TCK_R
R9B12  RES  1.00K 1% CHIP  pkg 0402  page 113 : 1 = P1V8_MCP_CPU0 ; 2 = JTAG_MCP_MUX_TDO
R9B13  RES  0.0 5% CHIP  pkg 0402  page 113 : 1 = JTAG_MCP_TMS ; 2 = JTAG_MCP_TMS_R
R9B14  RES  1.00K 1% CHIP  pkg 0402  page 113 : 1 = PWRGD_CPU0_G ; 2 = PWRGD_CPU0_G_R
R9E1  RES  10.0K 1% CHIP  pkg 0402  page 139 : 1 = P3V3_STBY ; 2 = PU_JTAG_SPRV_TDI
R9E2  RES  10.0K 1% CHIP  pkg 0402  page 139 : 1 = P3V3_STBY ; 2 = PU_JTAG_SPRV_TCK
R9E3  RES  10.0K 1% CHIP  pkg 0402  page 139 : 1 = P3V3_STBY ; 2 = PU_JTAG_SPRV_TMS
R9E4  RES  10.0K 1% CHIP  pkg 0402  page 139 : 1 = P3V3_STBY ; 2 = RST_PLTRST_SPRV_R_N
R9E5  RES  33.2 1% CHIP  pkg 0402  page 139 : 1 = SPI_NIC_CS_R_N ; 2 = SPI_NIC_CS_N
R9E6  RES  33.2 1% CHIP  pkg 0402  page 140 : 1 = SPI_NIC_MISO_R ; 2 = SPI_NIC_MISO
R9E7  RES  3.32K 1% CHIP  pkg 0402  page 139 : 1 = P3V3_STBY ; 2 = IRQ_LOM_ALERT_N
R9E8  RES  33.2 1% CHIP  pkg 0402  page 139 : 1 = SPI_NIC_SCLK_R ; 2 = SPI_NIC_SCLK
R9E9  RES  33.2 1% CHIP  pkg 0402  page 139 : 1 = SPI_NIC_MOSI_R ; 2 = SPI_NIC_MOSI
R9E10  RES  200.0 1% CHIP  pkg 0402  page 187 : 1 = RST_PCIE_CPU_DEV1_R_N ; 2 = RST_PCIE_CPU_DEV1_N
R9E11  RES  200.0 1% CHIP  pkg 0402  page 187 : 1 = RST_PCIE_CPU_DEV2_R_N ; 2 = RST_PCIE_CPU_DEV2_N
R9E12  RES  200.0 1% CHIP  pkg 0402  page 187 : 1 = RST_PCIE_CPU_DEV3_R_N ; 2 = RST_PCIE_CPU_DEV3_N
R9E13  RES  10.0K 1% CHIP  pkg 0402  page 139 : 1 = RMII_BMC_PCH_SPRNGVLLE_TXEN ; 2 = GND
R9E14  RES  0.0 5% EMPTY  pkg 0402  page 157 : 1 = FM_TPM_PRES_RST_N ; 2 = FM_BMC_ENABLE_N
R9E16  RES  33.2 1% CHIP  pkg 0402  page 139 : 1 = RMII_PCH_SPRNGVLLE_ARB_IN_R ; 2 = RMII_PCH_SPRNGVLLE_ARB_IN
R9E17  RES  22.1 1.0% CHIP  pkg 0402  page 139 : 1 = RMII_SPRNGVLLE_BMC_PCH_RXD0_R ; 2 = RMII_SPRNGVLLE_BMC_PCH_RXD0
R9E18  RES  0.0 5% CHIP  pkg 0402  page 139 : 1 = XTAL_25MHZ_OUT_R ; 2 = XTAL_25MHZ_OUT
R9E19  RES  22.1 1.0% CHIP  pkg 0402  page 139 : 1 = RMII_SPRNGVLLE_BMC_PCH_RXD1_R ; 2 = RMII_SPRNGVLLE_BMC_PCH_RXD1
R9E20  RES  0.0 5% CHIP  pkg 0402  page 139 : 1 = XTAL_25MHZ_IN ; 2 = XTAL_25MHZ_IN_R
R9E21  RES  4.75K 1% CHIP  pkg 0402  page 151 : 1 = P3V3_STBY ; 2 = FM_HEARTBEAT_LED
R9E22  RES  10.0K 1% CHIP  pkg 0402  page 139 : 1 = PU_JTAG_SPRV_TDO ; 2 = P3V3_STBY
R9E23  RES  4.99K 1% CHIP  pkg 0402  page 139 : 1 = PD_SPRV_RSET ; 2 = GND
R9E24  RES  221 1.0% CHIP  pkg 0402  page 151 : 1 = FM_HEARTBEAT_LED_A ; 2 = P3V3_STBY
R9F1  RES  22.1 1.0% CHIP  pkg 0402  page 139 : 1 = RMII_BMC_PCH_SPRNGVLLE_CRSDV_R ; 2 = RMII_BMC_PCH_SPRNGVLLE_CRSDV
R9F3  RES  4.75K 1% CHIP  pkg 0402  page 170 : 1 = P3V3_STBY ; 2 = FM_FAST_PROCHOT_EN
R9F5  RES  3.32K 1% CHIP  pkg 0402  page 139 : 1 = P3V3_STBY ; 2 = PU_SPRV_LAN_PWR_GOOD
R9F6  4K42R2F-GP  1%  pkg SMD-RG  page 238 : 1 = P1V15_AUX_BMC ; 2 = VR_P1V15_BMC_STBY_FB
R9F8  RES  10.0K 1% CHIP  pkg 0402  page 238 : 1 = GND ; 2 = VR_P1V15_BMC_STBY_FB
R9F11  RES  22.1 1.0% CHIP  pkg 0402  page 238 : 1 = PWRGD_P1V15_BMC_STBY_R ; 2 = PWRGD_P1V15_BMC_STBY
R9F12  RES  10.0K 1% CHIP  pkg 0402  page 239 : 1 = P3V3_STBY ; 2 = PWRGD_P1V2_BMC_STBY_R
R9F13  RES  10.0K 1% CHIP  pkg 0402  page 238 : 1 = P3V3_STBY ; 2 = PWRGD_P1V15_BMC_STBY_R
R9F20  RES  348 1% EMPTY  pkg 0402  page 145 : 1 = PECI_BMC ; 2 = GND
R9F22  RES  20.0 1% CHIP  pkg 0402  page 160 : 1 = SMB_LAN_STBY_LVC3_SCL_R ; 2 = SMB_LAN_STBY_LVC3_SCL
R9F23  RES  20.0 1% CHIP  pkg 0402  page 160 : 1 = SMB_LAN_STBY_LVC3_SDA_R ; 2 = SMB_LAN_STBY_LVC3_SDA
R9F24  RES  0.0 5% EMPTY  pkg 0402  page 158 : 1 = SPA_MID_DBG_RX ; 2 = SP2_BMC_CM_UART_RX
R9F25  RES  100.0 1% CHIP  pkg 0402  page 158 : 1 = SPA_MID_DBG_RX ; 2 = UART_MUX_IN_R
R9F26  RES  0.0 5% EMPTY  pkg 0402  page 158 : 1 = SP2_BMC_CM_UART_TX ; 2 = SPA_MID_DBG_TX
R9F27  RES  0.0 5% CHIP  pkg 0402  page 158 : 1 = UART_MUX_OUT_R ; 2 = SPA_MID_DBG_TX
R9F28  RES  221 1.0% CHIP  pkg 0402  page 177 : 1 = P3V3_STBY ; 2 = FM_RED_LED_ANODE
R9F29  RES  4.75K 1% CHIP  pkg 0402  page 151 : 1 = P1V2_AUX_BMC ; 2 = RST_BMC_DDR3_R_N
R9F30  RES  4.75K 1% CHIP  pkg 0402  page 177 : 1 = P3V3_STBY ; 2 = FM_BMC_FAULT_LED_N
R9F31  5K1R2F-2-GP  1%  pkg SMD-RG  page 239 : 1 = P1V2_AUX_BMC ; 2 = VR_P1V2_BMC_STBY_FB
R9F32  RES  10.0K 1% CHIP  pkg 0402  page 239 : 1 = VR_P1V2_BMC_STBY_FB ; 2 = GND
R9F33  RES  0.0 5% CHIP  pkg 0402  page 145 : 1 = PECI_BMC ; 2 = PECI_BMC_R
R9F34  RES  33.2 1% EMPTY  pkg 0402  page 151 : 1 = RST_BMC_DDR3_R_N ; 2 = BMC_M_RST_N
R9F52  RES  4.75K 1% CHIP  pkg 0402  page 177 : 1 = P3V3_STBY ; 2 = FM_BMC_FAULT_LED
R9F55  RES  4.75K 1% CHIP  pkg 0402  page 183 : 1 = P3V3_STBY ; 2 = FM_UART_ALERT_N
R9F60  RES  0.0 5% EMPTY  pkg 0402  page 145 : 1 = CLK_25M_BMC ; 2 = CLK_24M_25M_BMC_CLKIN
R9F61  RES  10.0K 1% CHIP  pkg 0402  page 145 : 1 = P3V3_STBY ; 2 = PU_24M_OSC_OE
R9F62  RES  0.0 5% CHIP  pkg 0402  page 145 : 1 = CLK_24M_BMC_CLKIN_R ; 2 = CLK_24M_25M_BMC_CLKIN
R9F63  RES  0.0 5% EMPTY  pkg 0402  page 181 : 1 = SPA_MID_DBG_RX ; 2 = SPA_MID_DBG_RX_R
R9F64  RES  0.0 5% CHIP  pkg 0402  page 181 : 1 = SP2_BMC_CM_UART_TX_R1 ; 2 = SPA_MID_DBG_RX_R
R9F65  RES  0.0 5% CHIP  pkg 0402  page 158 : 1 = SP2_BMC_CM_UART_TX_R1 ; 2 = SP2_BMC_CM_UART_TX_R
R9F66  RES  0.0 5% EMPTY  pkg 0402  page 158 : 1 = SP2_BMC_CM_UART_TX ; 2 = SP2_BMC_CM_UART_TX_R
R9F67  RES  0.0 5% CHIP  pkg 0402  page 181 : 1 = SP2_BMC_CM_UART_RX_R1 ; 2 = SPA_MID_DBG_TX_R
R9F68  RES  0.0 5% EMPTY  pkg 0402  page 158 : 1 = SP2_BMC_CM_UART_RX_R ; 2 = SP2_BMC_CM_UART_RX
R9F69  RES  0.0 5% CHIP  pkg 0402  page 158 : 1 = SP2_BMC_CM_UART_RX_R ; 2 = SP2_BMC_CM_UART_RX_R1
R9F70  RES  0.0 5% EMPTY  pkg 0402  page 181 : 1 = SPA_MID_DBG_TX ; 2 = SPA_MID_DBG_TX_R
R9G1  RES  150.0 1% CHIP  pkg 0402  page 141 : 1 = LED_LAN_1_N ; 2 = LED_LAN_1_R_N
R9G2  RES  75 1.0% CHIP  pkg 0402  page 141 : 1 = LED_LAN_2_R_N ; 2 = LED_LAN_2_N
R9G3  RES  75 1.0% CHIP  pkg 0402  page 141 : 1 = LED_LAN_0_R_N ; 2 = LED_LAN_0_N
R9G4  RES  0.0 5% CHIP  pkg 0402  page 141 : 1 = NIC_LED_ACT_ANODE_R ; 2 = P3V3_STBY
